(kicad_pcb
	(version 20260206)
	(generator "pcbnew")
	(generator_version "10.0")
	(general
		(thickness 1.6)
		(legacy_teardrops no)
	)
	(paper "A4")
	(title_block
		(title "Bryce Canyon_SCC_16316-1_OCP.brd")
		(comment 1 "Bryce Canyon / footprint 146 of 1561 (CN2), pads 220-300 of 342")
	)
	(layers
		(0 "F.Cu" signal "TOP")
		(4 "In1.Cu" signal "L2GND")
		(6 "In2.Cu" signal "L3")
		(8 "In3.Cu" signal "L4VCC")
		(10 "In4.Cu" signal "L5VCC")
		(12 "In5.Cu" signal "L6")
		(14 "In6.Cu" signal "L7GND")
		(2 "B.Cu" signal "BOTTOM")
		(9 "F.Adhes" user "F.Adhesive")
		(11 "B.Adhes" user "B.Adhesive")
		(13 "F.Paste" user "Package Geometry/Pastemask Top")
		(15 "B.Paste" user "Package Geometry/Pastemask Bottom")
		(5 "F.SilkS" user "Ref Des/Silkscreen Top")
		(7 "B.SilkS" user "Ref Des/Silkscreen Bottom")
		(1 "F.Mask" user "Board Geometry/Soldermask Top")
		(3 "B.Mask" user "Board Geometry/Soldermask Bottom")
		(17 "Dwgs.User" user "User.Drawings")
		(19 "Cmts.User" user "User.Comments")
		(21 "Eco1.User" user "User.Eco1")
		(23 "Eco2.User" user "User.Eco2")
		(25 "Edge.Cuts" user "Board Geometry/Outline")
		(27 "Margin" user)
		(31 "F.CrtYd" user "Package Geometry/Place Bound Top")
		(29 "B.CrtYd" user "Package Geometry/Place Bound Bottom")
		(35 "F.Fab" user "Ref Des/Assembly Top")
		(33 "B.Fab" user "Ref Des/Assembly Bottom")
	)
	(footprint ""
		(layer "F.Cu")
		(at 86.000082 -3.800094)
		(property "Reference" "CN2"
			(at 0 0 0)
			(layer "F.SilkS")
			(hide yes)
			(effects
				(font
					(size 1.27 1.27)
				)
			)
		)
		(property "Value" "AMP-CONN342-10R-3-GP"
			(at -12.8905 -12.5222 0)
			(unlocked yes)
			(layer "F.Fab")
			(hide yes)
			(effects
				(font
					(size 1.016 1.016)
					(thickness 0.1524)
				)
			)
		)
		(property "Device Type" "PREFIT-342P-648260H400"
			(at -12.8905 -14.0462 0)
			(unlocked yes)
			(layer "F.Fab")
			(hide yes)
			(effects
				(font
					(size 1.016 1.016)
					(thickness 0.1524)
				)
			)
		)
		(duplicate_pad_numbers_are_jumpers no)
		(pad "GND4" thru_hole circle
			(at 1.800098 2.29997)
			(size 0.762 0.762)
			(drill 0.359918)
			(layers "*.Cu" "*.Mask")
			(remove_unused_layers no)
			(net "GND")
			(clearance 0.1651)
			(thermal_gap 0.1651)
		)
		(pad "GND5" thru_hole circle
			(at 1.800098 -1.299972)
			(size 0.762 0.762)
			(drill 0.359918)
			(layers "*.Cu" "*.Mask")
			(remove_unused_layers no)
			(net "GND")
			(clearance 0.1651)
			(thermal_gap 0.1651)
		)
		(pad "GND6" thru_hole circle
			(at 1.800098 -4.899914)
			(size 0.762 0.762)
			(drill 0.359918)
			(layers "*.Cu" "*.Mask")
			(remove_unused_layers no)
			(net "GND")
			(clearance 0.1651)
			(thermal_gap 0.1651)
		)
		(pad "GND7" thru_hole circle
			(at 1.800098 -8.50011)
			(size 0.762 0.762)
			(drill 0.359918)
			(layers "*.Cu" "*.Mask")
			(remove_unused_layers no)
			(net "GND")
			(clearance 0.1651)
			(thermal_gap 0.1651)
		)
		(pad "GND8" thru_hole circle
			(at 3.599942 -2.500122)
			(size 0.762 0.762)
			(drill 0.359918)
			(layers "*.Cu" "*.Mask")
			(remove_unused_layers no)
			(net "GND")
			(clearance 0.1651)
			(thermal_gap 0.1651)
		)
		(pad "GND9" thru_hole circle
			(at 3.599942 -6.100064)
			(size 0.762 0.762)
			(drill 0.359918)
			(layers "*.Cu" "*.Mask")
			(remove_unused_layers no)
			(net "GND")
			(clearance 0.1651)
			(thermal_gap 0.1651)
		)
		(pad "GND10" thru_hole circle
			(at 3.599942 -9.700006)
			(size 0.762 0.762)
			(drill 0.359918)
			(layers "*.Cu" "*.Mask")
			(remove_unused_layers no)
			(net "GND")
			(clearance 0.1651)
			(thermal_gap 0.1651)
		)
		(pad "GND11" thru_hole circle
			(at 5.40004 2.29997)
			(size 0.762 0.762)
			(drill 0.359918)
			(layers "*.Cu" "*.Mask")
			(remove_unused_layers no)
			(net "GND")
			(clearance 0.1651)
			(thermal_gap 0.1651)
		)
		(pad "GND12" thru_hole circle
			(at 5.40004 -1.299972)
			(size 0.762 0.762)
			(drill 0.359918)
			(layers "*.Cu" "*.Mask")
			(remove_unused_layers no)
			(net "GND")
			(clearance 0.1651)
			(thermal_gap 0.1651)
		)
		(pad "GND13" thru_hole circle
			(at 5.40004 -4.899914)
			(size 0.762 0.762)
			(drill 0.359918)
			(layers "*.Cu" "*.Mask")
			(remove_unused_layers no)
			(net "GND")
			(clearance 0.1651)
			(thermal_gap 0.1651)
		)
		(pad "GND14" thru_hole circle
			(at 5.40004 -8.50011)
			(size 0.762 0.762)
			(drill 0.359918)
			(layers "*.Cu" "*.Mask")
			(remove_unused_layers no)
			(net "GND")
			(clearance 0.1651)
			(thermal_gap 0.1651)
		)
		(pad "GND15" thru_hole circle
			(at 7.199884 -2.500122)
			(size 0.762 0.762)
			(drill 0.359918)
			(layers "*.Cu" "*.Mask")
			(remove_unused_layers no)
			(net "GND")
			(clearance 0.1651)
			(thermal_gap 0.1651)
		)
		(pad "GND16" thru_hole circle
			(at 7.199884 -6.100064)
			(size 0.762 0.762)
			(drill 0.359918)
			(layers "*.Cu" "*.Mask")
			(remove_unused_layers no)
			(net "GND")
			(clearance 0.1651)
			(thermal_gap 0.1651)
		)
		(pad "GND17" thru_hole circle
			(at 7.199884 -9.700006)
			(size 0.762 0.762)
			(drill 0.359918)
			(layers "*.Cu" "*.Mask")
			(remove_unused_layers no)
			(net "GND")
			(clearance 0.1651)
			(thermal_gap 0.1651)
		)
		(pad "GND18" thru_hole circle
			(at 8.999982 2.29997)
			(size 0.762 0.762)
			(drill 0.359918)
			(layers "*.Cu" "*.Mask")
			(remove_unused_layers no)
			(net "GND")
			(clearance 0.1651)
			(thermal_gap 0.1651)
		)
		(pad "GND19" thru_hole circle
			(at 8.999982 -1.299972)
			(size 0.762 0.762)
			(drill 0.359918)
			(layers "*.Cu" "*.Mask")
			(remove_unused_layers no)
			(net "GND")
			(clearance 0.1651)
			(thermal_gap 0.1651)
		)
		(pad "GND20" thru_hole circle
			(at 8.999982 -4.899914)
			(size 0.762 0.762)
			(drill 0.359918)
			(layers "*.Cu" "*.Mask")
			(remove_unused_layers no)
			(net "GND")
			(clearance 0.1651)
			(thermal_gap 0.1651)
		)
		(pad "GND21" thru_hole circle
			(at 8.999982 -8.50011)
			(size 0.762 0.762)
			(drill 0.359918)
			(layers "*.Cu" "*.Mask")
			(remove_unused_layers no)
			(net "GND")
			(clearance 0.1651)
			(thermal_gap 0.1651)
		)
		(pad "GND22" thru_hole circle
			(at 10.80008 -2.500122)
			(size 0.762 0.762)
			(drill 0.359918)
			(layers "*.Cu" "*.Mask")
			(remove_unused_layers no)
			(net "GND")
			(clearance 0.1651)
			(thermal_gap 0.1651)
		)
		(pad "GND23" thru_hole circle
			(at 10.80008 -6.100064)
			(size 0.762 0.762)
			(drill 0.359918)
			(layers "*.Cu" "*.Mask")
			(remove_unused_layers no)
			(net "GND")
			(clearance 0.1651)
			(thermal_gap 0.1651)
		)
		(pad "GND24" thru_hole circle
			(at 10.80008 -9.700006)
			(size 0.762 0.762)
			(drill 0.359918)
			(layers "*.Cu" "*.Mask")
			(remove_unused_layers no)
			(net "GND")
			(clearance 0.1651)
			(thermal_gap 0.1651)
		)
		(pad "GND25" thru_hole circle
			(at 12.599924 2.29997)
			(size 0.762 0.762)
			(drill 0.359918)
			(layers "*.Cu" "*.Mask")
			(remove_unused_layers no)
			(net "GND")
			(clearance 0.1651)
			(thermal_gap 0.1651)
		)
		(pad "GND26" thru_hole circle
			(at 12.599924 -1.299972)
			(size 0.762 0.762)
			(drill 0.359918)
			(layers "*.Cu" "*.Mask")
			(remove_unused_layers no)
			(net "GND")
			(clearance 0.1651)
			(thermal_gap 0.1651)
		)
		(pad "GND27" thru_hole circle
			(at 12.599924 -4.899914)
			(size 0.762 0.762)
			(drill 0.359918)
			(layers "*.Cu" "*.Mask")
			(remove_unused_layers no)
			(net "GND")
			(clearance 0.1651)
			(thermal_gap 0.1651)
		)
		(pad "GND28" thru_hole circle
			(at 12.599924 -8.50011)
			(size 0.762 0.762)
			(drill 0.359918)
			(layers "*.Cu" "*.Mask")
			(remove_unused_layers no)
			(net "GND")
			(clearance 0.1651)
			(thermal_gap 0.1651)
		)
		(pad "GND29" thru_hole circle
			(at 14.400022 -2.500122)
			(size 0.762 0.762)
			(drill 0.359918)
			(layers "*.Cu" "*.Mask")
			(remove_unused_layers no)
			(net "GND")
			(clearance 0.1651)
			(thermal_gap 0.1651)
		)
		(pad "GND30" thru_hole circle
			(at 14.400022 -6.100064)
			(size 0.762 0.762)
			(drill 0.359918)
			(layers "*.Cu" "*.Mask")
			(remove_unused_layers no)
			(net "GND")
			(clearance 0.1651)
			(thermal_gap 0.1651)
		)
		(pad "GND31" thru_hole circle
			(at 14.400022 -9.700006)
			(size 0.762 0.762)
			(drill 0.359918)
			(layers "*.Cu" "*.Mask")
			(remove_unused_layers no)
			(net "GND")
			(clearance 0.1651)
			(thermal_gap 0.1651)
		)
		(pad "GND32" thru_hole circle
			(at 16.20012 2.29997)
			(size 0.762 0.762)
			(drill 0.359918)
			(layers "*.Cu" "*.Mask")
			(remove_unused_layers no)
			(net "GND")
			(clearance 0.1651)
			(thermal_gap 0.1651)
		)
		(pad "GND33" thru_hole circle
			(at 16.20012 -1.299972)
			(size 0.762 0.762)
			(drill 0.359918)
			(layers "*.Cu" "*.Mask")
			(remove_unused_layers no)
			(net "GND")
			(clearance 0.1651)
			(thermal_gap 0.1651)
		)
		(pad "GND34" thru_hole circle
			(at 16.20012 -4.899914)
			(size 0.762 0.762)
			(drill 0.359918)
			(layers "*.Cu" "*.Mask")
			(remove_unused_layers no)
			(net "GND")
			(clearance 0.1651)
			(thermal_gap 0.1651)
		)
		(pad "GND35" thru_hole circle
			(at 16.20012 -8.50011)
			(size 0.762 0.762)
			(drill 0.359918)
			(layers "*.Cu" "*.Mask")
			(remove_unused_layers no)
			(net "GND")
			(clearance 0.1651)
			(thermal_gap 0.1651)
		)
		(pad "GND36" thru_hole circle
			(at 17.999964 -2.500122)
			(size 0.762 0.762)
			(drill 0.359918)
			(layers "*.Cu" "*.Mask")
			(remove_unused_layers no)
			(net "GND")
			(clearance 0.1651)
			(thermal_gap 0.1651)
		)
		(pad "GND37" thru_hole circle
			(at 17.999964 -6.100064)
			(size 0.762 0.762)
			(drill 0.359918)
			(layers "*.Cu" "*.Mask")
			(remove_unused_layers no)
			(net "GND")
			(clearance 0.1651)
			(thermal_gap 0.1651)
		)
		(pad "GND38" thru_hole circle
			(at 17.999964 -9.700006)
			(size 0.762 0.762)
			(drill 0.359918)
			(layers "*.Cu" "*.Mask")
			(remove_unused_layers no)
			(net "GND")
			(clearance 0.1651)
			(thermal_gap 0.1651)
		)
		(pad "GND39" thru_hole circle
			(at 19.800062 2.29997)
			(size 0.762 0.762)
			(drill 0.359918)
			(layers "*.Cu" "*.Mask")
			(remove_unused_layers no)
			(net "GND")
			(clearance 0.1651)
			(thermal_gap 0.1651)
		)
		(pad "GND40" thru_hole circle
			(at 19.800062 -1.299972)
			(size 0.762 0.762)
			(drill 0.359918)
			(layers "*.Cu" "*.Mask")
			(remove_unused_layers no)
			(net "GND")
			(clearance 0.1651)
			(thermal_gap 0.1651)
		)
		(pad "GND41" thru_hole circle
			(at 19.800062 -4.899914)
			(size 0.762 0.762)
			(drill 0.359918)
			(layers "*.Cu" "*.Mask")
			(remove_unused_layers no)
			(net "GND")
			(clearance 0.1651)
			(thermal_gap 0.1651)
		)
		(pad "GND42" thru_hole circle
			(at 19.800062 -8.50011)
			(size 0.762 0.762)
			(drill 0.359918)
			(layers "*.Cu" "*.Mask")
			(remove_unused_layers no)
			(net "GND")
			(clearance 0.1651)
			(thermal_gap 0.1651)
		)
		(pad "GND43" thru_hole circle
			(at 21.599906 -2.500122)
			(size 0.762 0.762)
			(drill 0.359918)
			(layers "*.Cu" "*.Mask")
			(remove_unused_layers no)
			(net "GND")
			(clearance 0.1651)
			(thermal_gap 0.1651)
		)
		(pad "GND44" thru_hole circle
			(at 21.599906 -6.100064)
			(size 0.762 0.762)
			(drill 0.359918)
			(layers "*.Cu" "*.Mask")
			(remove_unused_layers no)
			(net "GND")
			(clearance 0.1651)
			(thermal_gap 0.1651)
		)
		(pad "GND45" thru_hole circle
			(at 21.599906 -9.700006)
			(size 0.762 0.762)
			(drill 0.359918)
			(layers "*.Cu" "*.Mask")
			(remove_unused_layers no)
			(net "GND")
			(clearance 0.1651)
			(thermal_gap 0.1651)
		)
		(pad "GND46" thru_hole circle
			(at 23.400004 2.29997)
			(size 0.762 0.762)
			(drill 0.359918)
			(layers "*.Cu" "*.Mask")
			(remove_unused_layers no)
			(net "GND")
			(clearance 0.1651)
			(thermal_gap 0.1651)
		)
		(pad "GND47" thru_hole circle
			(at 23.400004 -1.299972)
			(size 0.762 0.762)
			(drill 0.359918)
			(layers "*.Cu" "*.Mask")
			(remove_unused_layers no)
			(net "GND")
			(clearance 0.1651)
			(thermal_gap 0.1651)
		)
		(pad "GND48" thru_hole circle
			(at 23.400004 -4.899914)
			(size 0.762 0.762)
			(drill 0.359918)
			(layers "*.Cu" "*.Mask")
			(remove_unused_layers no)
			(net "GND")
			(clearance 0.1651)
			(thermal_gap 0.1651)
		)
		(pad "GND49" thru_hole circle
			(at 23.400004 -8.50011)
			(size 0.762 0.762)
			(drill 0.359918)
			(layers "*.Cu" "*.Mask")
			(remove_unused_layers no)
			(net "GND")
			(clearance 0.1651)
			(thermal_gap 0.1651)
		)
		(pad "GND50" thru_hole circle
			(at 25.200102 -2.500122)
			(size 0.762 0.762)
			(drill 0.359918)
			(layers "*.Cu" "*.Mask")
			(remove_unused_layers no)
			(net "GND")
			(clearance 0.1651)
			(thermal_gap 0.1651)
		)
		(pad "GND51" thru_hole circle
			(at 25.200102 -6.100064)
			(size 0.762 0.762)
			(drill 0.359918)
			(layers "*.Cu" "*.Mask")
			(remove_unused_layers no)
			(net "GND")
			(clearance 0.1651)
			(thermal_gap 0.1651)
		)
		(pad "GND52" thru_hole circle
			(at 25.200102 -9.700006)
			(size 0.762 0.762)
			(drill 0.359918)
			(layers "*.Cu" "*.Mask")
			(remove_unused_layers no)
			(net "GND")
			(clearance 0.1651)
			(thermal_gap 0.1651)
		)
		(pad "GND53" thru_hole circle
			(at 26.999946 2.29997)
			(size 0.762 0.762)
			(drill 0.359918)
			(layers "*.Cu" "*.Mask")
			(remove_unused_layers no)
			(net "GND")
			(clearance 0.1651)
			(thermal_gap 0.1651)
		)
		(pad "GND54" thru_hole circle
			(at 26.999946 -1.299972)
			(size 0.762 0.762)
			(drill 0.359918)
			(layers "*.Cu" "*.Mask")
			(remove_unused_layers no)
			(net "GND")
			(clearance 0.1651)
			(thermal_gap 0.1651)
		)
		(pad "GND55" thru_hole circle
			(at 26.999946 -4.899914)
			(size 0.762 0.762)
			(drill 0.359918)
			(layers "*.Cu" "*.Mask")
			(remove_unused_layers no)
			(net "GND")
			(clearance 0.1651)
			(thermal_gap 0.1651)
		)
		(pad "GND56" thru_hole circle
			(at 26.999946 -8.50011)
			(size 0.762 0.762)
			(drill 0.359918)
			(layers "*.Cu" "*.Mask")
			(remove_unused_layers no)
			(net "GND")
			(clearance 0.1651)
			(thermal_gap 0.1651)
		)
		(pad "GND57" thru_hole circle
			(at 28.800044 -2.500122)
			(size 0.762 0.762)
			(drill 0.359918)
			(layers "*.Cu" "*.Mask")
			(remove_unused_layers no)
			(net "GND")
			(clearance 0.1651)
			(thermal_gap 0.1651)
		)
		(pad "GND58" thru_hole circle
			(at 28.800044 -6.100064)
			(size 0.762 0.762)
			(drill 0.359918)
			(layers "*.Cu" "*.Mask")
			(remove_unused_layers no)
			(net "GND")
			(clearance 0.1651)
			(thermal_gap 0.1651)
		)
		(pad "GND59" thru_hole circle
			(at 28.800044 -9.700006)
			(size 0.762 0.762)
			(drill 0.359918)
			(layers "*.Cu" "*.Mask")
			(remove_unused_layers no)
			(net "GND")
			(clearance 0.1651)
			(thermal_gap 0.1651)
		)
		(pad "GND60" thru_hole circle
			(at 30.599888 2.29997)
			(size 0.762 0.762)
			(drill 0.359918)
			(layers "*.Cu" "*.Mask")
			(remove_unused_layers no)
			(net "GND")
			(clearance 0.1651)
			(thermal_gap 0.1651)
		)
		(pad "GND61" thru_hole circle
			(at 30.599888 -1.299972)
			(size 0.762 0.762)
			(drill 0.359918)
			(layers "*.Cu" "*.Mask")
			(remove_unused_layers no)
			(net "GND")
			(clearance 0.1651)
			(thermal_gap 0.1651)
		)
		(pad "GND62" thru_hole circle
			(at 30.599888 -4.899914)
			(size 0.762 0.762)
			(drill 0.359918)
			(layers "*.Cu" "*.Mask")
			(remove_unused_layers no)
			(net "GND")
			(clearance 0.1651)
			(thermal_gap 0.1651)
		)
		(pad "GND63" thru_hole circle
			(at 30.599888 -8.50011)
			(size 0.762 0.762)
			(drill 0.359918)
			(layers "*.Cu" "*.Mask")
			(remove_unused_layers no)
			(net "GND")
			(clearance 0.1651)
			(thermal_gap 0.1651)
		)
		(pad "GND64" thru_hole circle
			(at 32.399986 -2.500122)
			(size 0.762 0.762)
			(drill 0.359918)
			(layers "*.Cu" "*.Mask")
			(remove_unused_layers no)
			(net "GND")
			(clearance 0.1651)
			(thermal_gap 0.1651)
		)
		(pad "GND65" thru_hole circle
			(at 32.399986 -6.100064)
			(size 0.762 0.762)
			(drill 0.359918)
			(layers "*.Cu" "*.Mask")
			(remove_unused_layers no)
			(net "GND")
			(clearance 0.1651)
			(thermal_gap 0.1651)
		)
		(pad "GND66" thru_hole circle
			(at 32.399986 -9.700006)
			(size 0.762 0.762)
			(drill 0.359918)
			(layers "*.Cu" "*.Mask")
			(remove_unused_layers no)
			(net "GND")
			(clearance 0.1651)
			(thermal_gap 0.1651)
		)
		(pad "GND67" thru_hole circle
			(at 34.200084 2.29997)
			(size 0.762 0.762)
			(drill 0.359918)
			(layers "*.Cu" "*.Mask")
			(remove_unused_layers no)
			(net "GND")
			(clearance 0.1651)
			(thermal_gap 0.1651)
		)
		(pad "GND68" thru_hole circle
			(at 34.200084 -1.299972)
			(size 0.762 0.762)
			(drill 0.359918)
			(layers "*.Cu" "*.Mask")
			(remove_unused_layers no)
			(net "GND")
			(clearance 0.1651)
			(thermal_gap 0.1651)
		)
		(pad "GND69" thru_hole circle
			(at 34.200084 -4.899914)
			(size 0.762 0.762)
			(drill 0.359918)
			(layers "*.Cu" "*.Mask")
			(remove_unused_layers no)
			(net "GND")
			(clearance 0.1651)
			(thermal_gap 0.1651)
		)
		(pad "GND70" thru_hole circle
			(at 34.200084 -8.50011)
			(size 0.762 0.762)
			(drill 0.359918)
			(layers "*.Cu" "*.Mask")
			(remove_unused_layers no)
			(net "GND")
			(clearance 0.1651)
			(thermal_gap 0.1651)
		)
		(pad "GND71" thru_hole circle
			(at 35.999928 -2.500122)
			(size 0.762 0.762)
			(drill 0.359918)
			(layers "*.Cu" "*.Mask")
			(remove_unused_layers no)
			(net "GND")
			(clearance 0.1651)
			(thermal_gap 0.1651)
		)
		(pad "GND72" thru_hole circle
			(at 35.999928 -6.100064)
			(size 0.762 0.762)
			(drill 0.359918)
			(layers "*.Cu" "*.Mask")
			(remove_unused_layers no)
			(net "GND")
			(clearance 0.1651)
			(thermal_gap 0.1651)
		)
		(pad "GND73" thru_hole circle
			(at 35.999928 -9.700006)
			(size 0.762 0.762)
			(drill 0.359918)
			(layers "*.Cu" "*.Mask")
			(remove_unused_layers no)
			(net "GND")
			(clearance 0.1651)
			(thermal_gap 0.1651)
		)
		(pad "GND74" thru_hole circle
			(at 37.800026 2.29997)
			(size 0.762 0.762)
			(drill 0.359918)
			(layers "*.Cu" "*.Mask")
			(remove_unused_layers no)
			(net "GND")
			(clearance 0.1651)
			(thermal_gap 0.1651)
		)
		(pad "GND75" thru_hole circle
			(at 37.800026 -1.299972)
			(size 0.762 0.762)
			(drill 0.359918)
			(layers "*.Cu" "*.Mask")
			(remove_unused_layers no)
			(net "GND")
			(clearance 0.1651)
			(thermal_gap 0.1651)
		)
		(pad "GND76" thru_hole circle
			(at 37.800026 -4.899914)
			(size 0.762 0.762)
			(drill 0.359918)
			(layers "*.Cu" "*.Mask")
			(remove_unused_layers no)
			(net "GND")
			(clearance 0.1651)
			(thermal_gap 0.1651)
		)
		(pad "GND77" thru_hole circle
			(at 37.800026 -8.50011)
			(size 0.762 0.762)
			(drill 0.359918)
			(layers "*.Cu" "*.Mask")
			(remove_unused_layers no)
			(net "GND")
			(clearance 0.1651)
			(thermal_gap 0.1651)
		)
		(pad "GND78" thru_hole circle
			(at 39.600124 -2.500122)
			(size 0.762 0.762)
			(drill 0.359918)
			(layers "*.Cu" "*.Mask")
			(remove_unused_layers no)
			(net "GND")
			(clearance 0.1651)
			(thermal_gap 0.1651)
		)
		(pad "GND79" thru_hole circle
			(at 39.600124 -6.100064)
			(size 0.762 0.762)
			(drill 0.359918)
			(layers "*.Cu" "*.Mask")
			(remove_unused_layers no)
			(net "GND")
			(clearance 0.1651)
			(thermal_gap 0.1651)
		)
		(pad "GND80" thru_hole circle
			(at 39.600124 -9.700006)
			(size 0.762 0.762)
			(drill 0.359918)
			(layers "*.Cu" "*.Mask")
			(remove_unused_layers no)
			(net "GND")
			(clearance 0.1651)
			(thermal_gap 0.1651)
		)
		(pad "GND81" thru_hole circle
			(at 41.399968 2.29997)
			(size 0.762 0.762)
			(drill 0.359918)
			(layers "*.Cu" "*.Mask")
			(remove_unused_layers no)
			(net "GND")
			(clearance 0.1651)
			(thermal_gap 0.1651)
		)
		(pad "GND82" thru_hole circle
			(at 41.399968 -1.299972)
			(size 0.762 0.762)
			(drill 0.359918)
			(layers "*.Cu" "*.Mask")
			(remove_unused_layers no)
			(net "GND")
			(clearance 0.1651)
			(thermal_gap 0.1651)
		)
		(pad "GND83" thru_hole circle
			(at 41.399968 -4.899914)
			(size 0.762 0.762)
			(drill 0.359918)
			(layers "*.Cu" "*.Mask")
			(remove_unused_layers no)
			(net "GND")
			(clearance 0.1651)
			(thermal_gap 0.1651)
		)
		(pad "GND84" thru_hole circle
			(at 41.399968 -8.50011)
			(size 0.762 0.762)
			(drill 0.359918)
			(layers "*.Cu" "*.Mask")
			(remove_unused_layers no)
			(net "GND")
			(clearance 0.1651)
			(thermal_gap 0.1651)
		)
	)
)
